# S9S_MB_2U (Grand Teton) — schematic netlist excerpt (pin names and nets, part order shuffled) for the footprints in the layout excerpt that follows; sources: Cadence DE-HDL packaged netlist, KiCad conversion of 03242023_DA0F0TMBIJ0_F0T_Motherboard_J_brd_V01_OCP.brd

R573  Q_RES  4.7K 1% EMPTY  pkg 0402LF  page 206 : A = P3V3 ; B = FM_DB2000_VSBEN
R739  Q_RES  10K 1% CHIP  pkg 0402LF  page 133 : A = P3V3_AUX ; B = FM_CPU1_SKTOCC_N

(kicad_pcb
	(version 20260206)
	(generator "pcbnew")
	(generator_version "10.0")
	(general
		(thickness 1.6)
		(legacy_teardrops no)
	)
	(paper "A4")
	(title_block
		(title "03242023_DA0F0TMBIJ0_F0T_Motherboard_J_brd_V01_OCP.brd")
		(comment 1 "Grand Teton / footprints 4540-4541 of 6105")
	)
	(layers
		(0 "F.Cu" signal "TOP")
		(4 "In1.Cu" signal "GND")
		(6 "In2.Cu" signal "IN1")
		(8 "In3.Cu" signal "GND1")
		(10 "In4.Cu" signal "IN2")
		(12 "In5.Cu" signal "GND2")
		(14 "In6.Cu" signal "IN3")
		(16 "In7.Cu" signal "GND3")
		(18 "In8.Cu" signal "VCC")
		(20 "In9.Cu" signal "VCC1")
		(22 "In10.Cu" signal "GND4")
		(24 "In11.Cu" signal "IN4")
		(26 "In12.Cu" signal "GND5")
		(28 "In13.Cu" signal "IN5")
		(30 "In14.Cu" signal "GND6")
		(32 "In15.Cu" signal "IN6")
		(34 "In16.Cu" signal "GND7")
		(2 "B.Cu" signal "BOTTOM")
		(9 "F.Adhes" user "F.Adhesive")
		(11 "B.Adhes" user "B.Adhesive")
		(13 "F.Paste" user "Package Geometry/Pastemask Top")
		(15 "B.Paste" user "Package Geometry/Pastemask Bottom")
		(5 "F.SilkS" user "Ref Des/Silkscreen Top")
		(7 "B.SilkS" user "Ref Des/Silkscreen Bottom")
		(1 "F.Mask" user "Board Geometry/Soldermask Top")
		(3 "B.Mask" user "Board Geometry/Soldermask Bottom")
		(17 "Dwgs.User" user "User.Drawings")
		(19 "Cmts.User" user "User.Comments")
		(21 "Eco1.User" user "User.Eco1")
		(23 "Eco2.User" user "User.Eco2")
		(25 "Edge.Cuts" user "Board Geometry/Outline")
		(27 "Margin" user)
		(31 "F.CrtYd" user "Package Geometry/Place Bound Top")
		(29 "B.CrtYd" user "Package Geometry/Place Bound Bottom")
		(35 "F.Fab" user "Ref Des/Assembly Top")
		(33 "B.Fab" user "Ref Des/Assembly Bottom")
	)
	(footprint ""
		(layer "B.Cu")
		(at 200.031858 -194.01917)
		(property "Reference" "R739"
			(at 0 0 0)
			(layer "B.SilkS")
			(hide yes)
			(effects
				(font
					(size 1.27 1.27)
				)
				(justify mirror)
			)
		)
		(property "Value" ""
			(at 0 0 0)
			(layer "B.Fab")
			(effects
				(font
					(size 1.27 1.27)
				)
				(justify mirror)
			)
		)
		(duplicate_pad_numbers_are_jumpers no)
		(fp_line
			(start -0.7874 -0.4064)
			(end -0.7874 0.4064)
			(stroke
				(width 0.1524)
				(type default)
			)
			(layer "B.SilkS")
		)
		(fp_line
			(start -0.7874 0.4064)
			(end 0.7874 0.4064)
			(stroke
				(width 0.1524)
				(type default)
			)
			(layer "B.SilkS")
		)
		(fp_line
			(start 0.7874 -0.4064)
			(end -0.7874 -0.4064)
			(stroke
				(width 0.1524)
				(type default)
			)
			(layer "B.SilkS")
		)
		(fp_line
			(start 0.7874 0.4064)
			(end 0.7874 -0.4064)
			(stroke
				(width 0.1524)
				(type default)
			)
			(layer "B.SilkS")
		)
		(fp_line
			(start -0.67945 -0.3048)
			(end -0.67945 0.3048)
			(stroke
				(width 0.1)
				(type default)
			)
			(layer "B.Fab")
		)
		(fp_line
			(start -0.67945 0.3048)
			(end -0.120396 0.3048)
			(stroke
				(width 0.1)
				(type default)
			)
			(layer "B.Fab")
		)
		(fp_line
			(start -0.12065 -0.3048)
			(end -0.67945 -0.3048)
			(stroke
				(width 0.1)
				(type default)
			)
			(layer "B.Fab")
		)
		(fp_line
			(start -0.12065 -0.2794)
			(end -0.12065 -0.3048)
			(stroke
				(width 0.1)
				(type default)
			)
			(layer "B.Fab")
		)
		(fp_line
			(start -0.120396 0.2794)
			(end 0.12065 0.2794)
			(stroke
				(width 0.1)
				(type default)
			)
			(layer "B.Fab")
		)
		(fp_line
			(start -0.120396 0.3048)
			(end -0.120396 0.2794)
			(stroke
				(width 0.1)
				(type default)
			)
			(layer "B.Fab")
		)
		(fp_line
			(start 0.12065 -0.305054)
			(end 0.12065 -0.2794)
			(stroke
				(width 0.1)
				(type default)
			)
			(layer "B.Fab")
		)
		(fp_line
			(start 0.12065 -0.2794)
			(end -0.12065 -0.2794)
			(stroke
				(width 0.1)
				(type default)
			)
			(layer "B.Fab")
		)
		(fp_line
			(start 0.12065 0.2794)
			(end 0.12065 0.3048)
			(stroke
				(width 0.1)
				(type default)
			)
			(layer "B.Fab")
		)
		(fp_line
			(start 0.12065 0.3048)
			(end 0.67945 0.3048)
			(stroke
				(width 0.1)
				(type default)
			)
			(layer "B.Fab")
		)
		(fp_line
			(start 0.67945 -0.305054)
			(end 0.12065 -0.305054)
			(stroke
				(width 0.1)
				(type default)
			)
			(layer "B.Fab")
		)
		(fp_line
			(start 0.67945 0.3048)
			(end 0.67945 -0.305054)
			(stroke
				(width 0.1)
				(type default)
			)
			(layer "B.Fab")
		)
		(pad "1" smd circle
			(at 0.40005 0 180)
			(size 0 0)
			(layers "B.Cu" "B.Mask" "B.Paste")
			(net "P3V3_AUX")
		)
		(pad "2" smd circle
			(at -0.40005 0 180)
			(size 0 0)
			(layers "B.Cu" "B.Mask" "B.Paste")
			(net "FM_CPU1_SKTOCC_N")
		)
	)
	(footprint ""
		(layer "B.Cu")
		(at 237.842806 -125.400054)
		(property "Reference" "R573"
			(at 0 0 0)
			(layer "B.SilkS")
			(hide yes)
			(effects
				(font
					(size 1.27 1.27)
				)
				(justify mirror)
			)
		)
		(property "Value" ""
			(at 0 0 0)
			(layer "B.Fab")
			(effects
				(font
					(size 1.27 1.27)
				)
				(justify mirror)
			)
		)
		(duplicate_pad_numbers_are_jumpers no)
		(fp_line
			(start -0.7874 -0.4064)
			(end -0.7874 0.4064)
			(stroke
				(width 0.1524)
				(type default)
			)
			(layer "B.SilkS")
		)
		(fp_line
			(start -0.7874 0.4064)
			(end 0.7874 0.4064)
			(stroke
				(width 0.1524)
				(type default)
			)
			(layer "B.SilkS")
		)
		(fp_line
			(start 0.7874 -0.4064)
			(end -0.7874 -0.4064)
			(stroke
				(width 0.1524)
				(type default)
			)
			(layer "B.SilkS")
		)
		(fp_line
			(start 0.7874 0.4064)
			(end 0.7874 -0.4064)
			(stroke
				(width 0.1524)
				(type default)
			)
			(layer "B.SilkS")
		)
		(fp_line
			(start -0.67945 -0.3048)
			(end -0.67945 0.3048)
			(stroke
				(width 0.1)
				(type default)
			)
			(layer "B.Fab")
		)
		(fp_line
			(start -0.67945 0.3048)
			(end -0.120396 0.3048)
			(stroke
				(width 0.1)
				(type default)
			)
			(layer "B.Fab")
		)
		(fp_line
			(start -0.12065 -0.3048)
			(end -0.67945 -0.3048)
			(stroke
				(width 0.1)
				(type default)
			)
			(layer "B.Fab")
		)
		(fp_line
			(start -0.12065 -0.2794)
			(end -0.12065 -0.3048)
			(stroke
				(width 0.1)
				(type default)
			)
			(layer "B.Fab")
		)
		(fp_line
			(start -0.120396 0.2794)
			(end 0.12065 0.2794)
			(stroke
				(width 0.1)
				(type default)
			)
			(layer "B.Fab")
		)
		(fp_line
			(start -0.120396 0.3048)
			(end -0.120396 0.2794)
			(stroke
				(width 0.1)
				(type default)
			)
			(layer "B.Fab")
		)
		(fp_line
			(start 0.12065 -0.305054)
			(end 0.12065 -0.2794)
			(stroke
				(width 0.1)
				(type default)
			)
			(layer "B.Fab")
		)
		(fp_line
			(start 0.12065 -0.2794)
			(end -0.12065 -0.2794)
			(stroke
				(width 0.1)
				(type default)
			)
			(layer "B.Fab")
		)
		(fp_line
			(start 0.12065 0.2794)
			(end 0.12065 0.3048)
			(stroke
				(width 0.1)
				(type default)
			)
			(layer "B.Fab")
		)
		(fp_line
			(start 0.12065 0.3048)
			(end 0.67945 0.3048)
			(stroke
				(width 0.1)
				(type default)
			)
			(layer "B.Fab")
		)
		(fp_line
			(start 0.67945 -0.305054)
			(end 0.12065 -0.305054)
			(stroke
				(width 0.1)
				(type default)
			)
			(layer "B.Fab")
		)
		(fp_line
			(start 0.67945 0.3048)
			(end 0.67945 -0.305054)
			(stroke
				(width 0.1)
				(type default)
			)
			(layer "B.Fab")
		)
		(pad "1" smd circle
			(at 0.40005 0 180)
			(size 0 0)
			(layers "B.Cu" "B.Mask" "B.Paste")
			(net "P3V3")
		)
		(pad "2" smd circle
			(at -0.40005 0 180)
			(size 0 0)
			(layers "B.Cu" "B.Mask" "B.Paste")
			(net "FM_DB2000_VSBEN")
		)
	)
)
